# BASEBOARD_FAB2 (Tioga Pass) — schematic netlist excerpt (pin names and nets, part order shuffled) for the footprints in the layout excerpt that follows; sources: Cadence DE-HDL packaged netlist, KiCad conversion of Wiwynn_Tioga_Pass_MB.brd

R3B2  RES  49.9 1% CHIP  pkg 0402  page 55 : A = SVID_ALERT0_CPU1_R_N ; B = PVCCIO_CPU1
C6B19  CAP  0.22UF 16V 10% X7R  pkg 0402  page 105 : A = P3E_CPU0_PE1_PCH_TXN<8> ; B = P3E_CPU0_PE1_PCH_C_TXN<8>
C5D22  CAP_A  22.0UF 4V 20% X6S  pkg 0603V  page 42 : A = PVCCMCP_CPU0 ; B = GND

(kicad_pcb
	(version 20260206)
	(generator "pcbnew")
	(generator_version "10.0")
	(general
		(thickness 1.6)
		(legacy_teardrops no)
	)
	(paper "A4")
	(title_block
		(title "Wiwynn_Tioga_Pass_MB.brd")
		(comment 1 "Tioga Pass / footprints 2273-2275 of 4770")
	)
	(layers
		(0 "F.Cu" signal "TOP")
		(4 "In1.Cu" signal "L2GND")
		(6 "In2.Cu" signal "L3")
		(8 "In3.Cu" signal "L4GND")
		(10 "In4.Cu" signal "L5")
		(12 "In5.Cu" signal "L6GND")
		(14 "In6.Cu" signal "L7VCC")
		(16 "In7.Cu" signal "L8VCC")
		(18 "In8.Cu" signal "L9GND")
		(20 "In9.Cu" signal "L10")
		(22 "In10.Cu" signal "L11GND")
		(24 "In11.Cu" signal "L12")
		(26 "In12.Cu" signal "L13GND")
		(2 "B.Cu" signal "BOTTOM")
		(9 "F.Adhes" user "F.Adhesive")
		(11 "B.Adhes" user "B.Adhesive")
		(13 "F.Paste" user "Package Geometry/Pastemask Top")
		(15 "B.Paste" user "Package Geometry/Pastemask Bottom")
		(5 "F.SilkS" user "Ref Des/Silkscreen Top")
		(7 "B.SilkS" user "Ref Des/Silkscreen Bottom")
		(1 "F.Mask" user "Board Geometry/Soldermask Top")
		(3 "B.Mask" user "Board Geometry/Soldermask Bottom")
		(17 "Dwgs.User" user "User.Drawings")
		(19 "Cmts.User" user "User.Comments")
		(21 "Eco1.User" user "User.Eco1")
		(23 "Eco2.User" user "User.Eco2")
		(25 "Edge.Cuts" user "Board Geometry/Outline")
		(27 "Margin" user)
		(31 "F.CrtYd" user "Package Geometry/Place Bound Top")
		(29 "B.CrtYd" user "Package Geometry/Place Bound Bottom")
		(35 "F.Fab" user "Ref Des/Assembly Top")
		(33 "B.Fab" user "Ref Des/Assembly Bottom")
	)
	(footprint ""
		(layer "F.Cu")
		(at 332.90002 -118.5164 90)
		(property "Reference" "C6B19"
			(at -0.8382 -0.67818 90)
			(unlocked yes)
			(layer "F.SilkS")
			(effects
				(font
					(size 0.4064 0.254)
					(thickness 0.1524)
				)
				(justify left)
			)
		)
		(property "Value" ""
			(at 0 0 90)
			(layer "F.Fab")
			(effects
				(font
					(size 1.27 1.27)
				)
			)
		)
		(duplicate_pad_numbers_are_jumpers no)
		(fp_poly
			(pts
				(xy 0.3048 -0.1016) (xy 0.3048 0.9906) (xy -0.3048 0.9906) (xy -0.3048 -0.1016)
			)
			(stroke
				(width 0)
				(type default)
			)
			(fill no)
			(layer "F.CrtYd")
		)
		(fp_line
			(start 0.3048 -0.1016)
			(end -0.3048 -0.1016)
			(stroke
				(width 0.1)
				(type default)
			)
			(layer "F.Fab")
		)
		(fp_line
			(start -0.3048 -0.1016)
			(end -0.3048 0.9906)
			(stroke
				(width 0.1)
				(type default)
			)
			(layer "F.Fab")
		)
		(fp_line
			(start 0.3048 0.9906)
			(end 0.3048 -0.1016)
			(stroke
				(width 0.1)
				(type default)
			)
			(layer "F.Fab")
		)
		(fp_line
			(start -0.3048 0.9906)
			(end 0.3048 0.9906)
			(stroke
				(width 0.1)
				(type default)
			)
			(layer "F.Fab")
		)
		(pad "1" smd rect
			(at 0 0 90)
			(size 0.508 0.508)
			(layers "F.Cu" "F.Mask" "F.Paste")
			(net "P3E_CPU0_PE1_PCH_TXN<8>")
		)
		(pad "2" smd rect
			(at 0 0.889 90)
			(size 0.508 0.508)
			(layers "F.Cu" "F.Mask" "F.Paste")
			(net "P3E_CPU0_PE1_PCH_C_TXN<8>")
		)
		(zone
			(layer "F.Cu")
			(hatch none 0.5)
			(connect_pads
				(clearance 0)
			)
			(min_thickness 0.25)
			(keepout
				(tracks allowed)
				(vias not_allowed)
				(pads allowed)
				(copperpour not_allowed)
				(footprints allowed)
			)
			(placement
				(enabled no)
				(sheetname "")
			)
			(fill
				(thermal_gap 0.5)
				(thermal_bridge_width 0.5)
				(island_removal_mode 0)
			)
			(polygon
				(pts
					(xy 333.15402 -118.2624) (xy 333.15402 -118.7704) (xy 333.53502 -118.7704) (xy 333.53502 -118.2624)
				)
			)
		)
		(zone
			(layer "F.Cu")
			(hatch none 0.5)
			(connect_pads
				(clearance 0)
			)
			(min_thickness 0.25)
			(keepout
				(tracks not_allowed)
				(vias allowed)
				(pads allowed)
				(copperpour not_allowed)
				(footprints allowed)
			)
			(placement
				(enabled no)
				(sheetname "")
			)
			(fill
				(thermal_gap 0.5)
				(thermal_bridge_width 0.5)
				(island_removal_mode 0)
			)
			(polygon
				(pts
					(xy 333.53502 -118.2624) (xy 333.53502 -118.7704) (xy 333.15402 -118.7704) (xy 333.15402 -118.2624)
				)
			)
		)
	)
	(footprint ""
		(layer "F.Cu")
		(at 157.988 -120.080786 90)
		(property "Reference" "R3B2"
			(at 0 0 90)
			(layer "F.SilkS")
			(hide yes)
			(effects
				(font
					(size 1.27 1.27)
				)
			)
		)
		(property "Value" ""
			(at 0 0 90)
			(layer "F.Fab")
			(effects
				(font
					(size 1.27 1.27)
				)
			)
		)
		(duplicate_pad_numbers_are_jumpers no)
		(fp_poly
			(pts
				(xy -0.2794 -0.1016) (xy 0.2794 -0.1016) (xy 0.2794 0.9906) (xy -0.2794 0.9906)
			)
			(stroke
				(width 0)
				(type default)
			)
			(fill no)
			(layer "F.CrtYd")
		)
		(fp_line
			(start 0.2794 -0.1016)
			(end -0.2794 -0.1016)
			(stroke
				(width 0.1)
				(type default)
			)
			(layer "F.Fab")
		)
		(fp_line
			(start -0.2794 -0.1016)
			(end -0.2794 0.9906)
			(stroke
				(width 0.1)
				(type default)
			)
			(layer "F.Fab")
		)
		(fp_line
			(start 0.2794 0.9906)
			(end 0.2794 -0.1016)
			(stroke
				(width 0.1)
				(type default)
			)
			(layer "F.Fab")
		)
		(fp_line
			(start -0.2794 0.9906)
			(end 0.2794 0.9906)
			(stroke
				(width 0.1)
				(type default)
			)
			(layer "F.Fab")
		)
		(pad "1" smd rect
			(at 0 0 90)
			(size 0.508 0.508)
			(layers "F.Cu" "F.Mask" "F.Paste")
			(net "SVID_ALERT0_CPU1_R_N")
		)
		(pad "2" smd rect
			(at 0 0.889 90)
			(size 0.508 0.508)
			(layers "F.Cu" "F.Mask" "F.Paste")
			(net "PVCCIO_CPU1")
		)
		(zone
			(layer "F.Cu")
			(hatch none 0.5)
			(connect_pads
				(clearance 0)
			)
			(min_thickness 0.25)
			(keepout
				(tracks allowed)
				(vias not_allowed)
				(pads allowed)
				(copperpour not_allowed)
				(footprints allowed)
			)
			(placement
				(enabled no)
				(sheetname "")
			)
			(fill
				(thermal_gap 0.5)
				(thermal_bridge_width 0.5)
				(island_removal_mode 0)
			)
			(polygon
				(pts
					(xy 158.242 -119.826786) (xy 158.242 -120.334786) (xy 158.623 -120.334786) (xy 158.623 -119.826786)
				)
			)
		)
		(zone
			(layer "F.Cu")
			(hatch none 0.5)
			(connect_pads
				(clearance 0)
			)
			(min_thickness 0.25)
			(keepout
				(tracks not_allowed)
				(vias allowed)
				(pads allowed)
				(copperpour not_allowed)
				(footprints allowed)
			)
			(placement
				(enabled no)
				(sheetname "")
			)
			(fill
				(thermal_gap 0.5)
				(thermal_bridge_width 0.5)
				(island_removal_mode 0)
			)
			(polygon
				(pts
					(xy 158.623 -119.826786) (xy 158.623 -120.334786) (xy 158.242 -120.334786) (xy 158.242 -119.826786)
				)
			)
		)
	)
	(footprint ""
		(layer "F.Cu")
		(at 274.5232 -79.6036 180)
		(property "Reference" "C5D22"
			(at 0 0 180)
			(layer "F.SilkS")
			(hide yes)
			(effects
				(font
					(size 1.27 1.27)
				)
			)
		)
		(property "Value" ""
			(at 0 0 180)
			(layer "F.Fab")
			(effects
				(font
					(size 1.27 1.27)
				)
			)
		)
		(duplicate_pad_numbers_are_jumpers no)
		(fp_poly
			(pts
				(xy -0.4953 -0.2032) (xy 0.4953 -0.2032) (xy 0.4953 1.6002) (xy -0.4953 1.6002)
			)
			(stroke
				(width 0)
				(type default)
			)
			(fill no)
			(layer "F.CrtYd")
		)
		(fp_line
			(start 0.4953 1.6002)
			(end -0.4953 1.6002)
			(stroke
				(width 0.1)
				(type default)
			)
			(layer "F.Fab")
		)
		(fp_line
			(start 0.4953 -0.2032)
			(end 0.4953 1.6002)
			(stroke
				(width 0.1)
				(type default)
			)
			(layer "F.Fab")
		)
		(fp_line
			(start -0.4953 1.6002)
			(end -0.4953 -0.2032)
			(stroke
				(width 0.1)
				(type default)
			)
			(layer "F.Fab")
		)
		(fp_line
			(start -0.4953 -0.2032)
			(end 0.4953 -0.2032)
			(stroke
				(width 0.1)
				(type default)
			)
			(layer "F.Fab")
		)
		(pad "1" smd rect
			(at 0 0 180)
			(size 0.762 0.889)
			(layers "F.Cu" "F.Mask" "F.Paste")
			(net "PVCCMCP_CPU0")
		)
		(pad "2" smd rect
			(at 0 1.397 180)
			(size 0.762 0.889)
			(layers "F.Cu" "F.Mask" "F.Paste")
			(net "GND")
		)
		(zone
			(layer "F.Cu")
			(hatch none 0.5)
			(connect_pads
				(clearance 0)
			)
			(min_thickness 0.25)
			(keepout
				(tracks not_allowed)
				(vias allowed)
				(pads allowed)
				(copperpour not_allowed)
				(footprints allowed)
			)
			(placement
				(enabled no)
				(sheetname "")
			)
			(fill
				(thermal_gap 0.5)
				(thermal_bridge_width 0.5)
				(island_removal_mode 0)
			)
			(polygon
				(pts
					(xy 274.9042 -80.0481) (xy 274.1422 -80.0481) (xy 274.1422 -80.5561) (xy 274.9042 -80.5561)
				)
			)
		)
	)
)
